# BASEBOARD_FAB2 (Tioga Pass) — schematic netlist excerpt (pin names and nets, part order shuffled) for the footprints in the layout excerpt that follows; sources: Cadence DE-HDL packaged netlist, KiCad conversion of Wiwynn_Tioga_Pass_MB.brd

C22W19  SC22U16V5MX-4-GP  20%  pkg SMD-BCG5  page 214 : \1\ = VR_FET_SW_P12V_STBY_PVCCIN_CPU0 ; \2\ = GND
R7G19  RES  0.0 5% EMPTY  pkg 0402  page 189 : A = JTAG_PCH_GBE_TDI ; B = JTAG_TDI
R12W26  RES  0.0 5% EMPTY  pkg 0402  page 215 : A = TP_PVDDQ_ABC_MP1 ; B = PWRGD_PVDDQ_ABC

(kicad_pcb
	(version 20260206)
	(generator "pcbnew")
	(generator_version "10.0")
	(general
		(thickness 1.6)
		(legacy_teardrops no)
	)
	(paper "A4")
	(title_block
		(title "Wiwynn_Tioga_Pass_MB.brd")
		(comment 1 "Tioga Pass / footprints 2222-2224 of 4770")
	)
	(layers
		(0 "F.Cu" signal "TOP")
		(4 "In1.Cu" signal "L2GND")
		(6 "In2.Cu" signal "L3")
		(8 "In3.Cu" signal "L4GND")
		(10 "In4.Cu" signal "L5")
		(12 "In5.Cu" signal "L6GND")
		(14 "In6.Cu" signal "L7VCC")
		(16 "In7.Cu" signal "L8VCC")
		(18 "In8.Cu" signal "L9GND")
		(20 "In9.Cu" signal "L10")
		(22 "In10.Cu" signal "L11GND")
		(24 "In11.Cu" signal "L12")
		(26 "In12.Cu" signal "L13GND")
		(2 "B.Cu" signal "BOTTOM")
		(9 "F.Adhes" user "F.Adhesive")
		(11 "B.Adhes" user "B.Adhesive")
		(13 "F.Paste" user "Package Geometry/Pastemask Top")
		(15 "B.Paste" user "Package Geometry/Pastemask Bottom")
		(5 "F.SilkS" user "Ref Des/Silkscreen Top")
		(7 "B.SilkS" user "Ref Des/Silkscreen Bottom")
		(1 "F.Mask" user "Board Geometry/Soldermask Top")
		(3 "B.Mask" user "Board Geometry/Soldermask Bottom")
		(17 "Dwgs.User" user "User.Drawings")
		(19 "Cmts.User" user "User.Comments")
		(21 "Eco1.User" user "User.Eco1")
		(23 "Eco2.User" user "User.Eco2")
		(25 "Edge.Cuts" user "Board Geometry/Outline")
		(27 "Margin" user)
		(31 "F.CrtYd" user "Package Geometry/Place Bound Top")
		(29 "B.CrtYd" user "Package Geometry/Place Bound Bottom")
		(35 "F.Fab" user "Ref Des/Assembly Top")
		(33 "B.Fab" user "Ref Des/Assembly Bottom")
	)
	(footprint ""
		(layer "F.Cu")
		(at 388.8232 -0.254)
		(property "Reference" "R7G19"
			(at 0 0 0)
			(layer "F.SilkS")
			(hide yes)
			(effects
				(font
					(size 1.27 1.27)
				)
			)
		)
		(property "Value" ""
			(at 0 0 0)
			(layer "F.Fab")
			(effects
				(font
					(size 1.27 1.27)
				)
			)
		)
		(duplicate_pad_numbers_are_jumpers no)
		(fp_poly
			(pts
				(xy -0.2794 -0.1016) (xy 0.2794 -0.1016) (xy 0.2794 0.9906) (xy -0.2794 0.9906)
			)
			(stroke
				(width 0)
				(type default)
			)
			(fill no)
			(layer "F.CrtYd")
		)
		(fp_line
			(start -0.2794 -0.1016)
			(end -0.2794 0.9906)
			(stroke
				(width 0.1)
				(type default)
			)
			(layer "F.Fab")
		)
		(fp_line
			(start -0.2794 0.9906)
			(end 0.2794 0.9906)
			(stroke
				(width 0.1)
				(type default)
			)
			(layer "F.Fab")
		)
		(fp_line
			(start 0.2794 -0.1016)
			(end -0.2794 -0.1016)
			(stroke
				(width 0.1)
				(type default)
			)
			(layer "F.Fab")
		)
		(fp_line
			(start 0.2794 0.9906)
			(end 0.2794 -0.1016)
			(stroke
				(width 0.1)
				(type default)
			)
			(layer "F.Fab")
		)
		(pad "1" smd rect
			(at 0 0)
			(size 0.508 0.508)
			(layers "F.Cu" "F.Mask" "F.Paste")
			(net "JTAG_PCH_GBE_TDI")
		)
		(pad "2" smd rect
			(at 0 0.889)
			(size 0.508 0.508)
			(layers "F.Cu" "F.Mask" "F.Paste")
			(net "JTAG_TDI")
		)
		(zone
			(layer "F.Cu")
			(hatch none 0.5)
			(connect_pads
				(clearance 0)
			)
			(min_thickness 0.25)
			(keepout
				(tracks allowed)
				(vias not_allowed)
				(pads allowed)
				(copperpour not_allowed)
				(footprints allowed)
			)
			(placement
				(enabled no)
				(sheetname "")
			)
			(fill
				(thermal_gap 0.5)
				(thermal_bridge_width 0.5)
				(island_removal_mode 0)
			)
			(polygon
				(pts
					(xy 388.5692 0) (xy 389.0772 0) (xy 389.0772 0.381) (xy 388.5692 0.381)
				)
			)
		)
		(zone
			(layer "F.Cu")
			(hatch none 0.5)
			(connect_pads
				(clearance 0)
			)
			(min_thickness 0.25)
			(keepout
				(tracks not_allowed)
				(vias allowed)
				(pads allowed)
				(copperpour not_allowed)
				(footprints allowed)
			)
			(placement
				(enabled no)
				(sheetname "")
			)
			(fill
				(thermal_gap 0.5)
				(thermal_bridge_width 0.5)
				(island_removal_mode 0)
			)
			(polygon
				(pts
					(xy 388.5692 0.381) (xy 389.0772 0.381) (xy 389.0772 0) (xy 388.5692 0)
				)
			)
		)
	)
	(footprint ""
		(layer "F.Cu")
		(at 176.037494 -58.982356)
		(property "Reference" "C22W19"
			(at 0 0 0)
			(layer "F.SilkS")
			(hide yes)
			(effects
				(font
					(size 1.27 1.27)
				)
			)
		)
		(property "Value" "*"
			(at -0.0762 -6.2357 0)
			(unlocked yes)
			(layer "F.Fab")
			(hide yes)
			(effects
				(font
					(size 1.27 1.016)
					(thickness 0.1524)
				)
			)
		)
		(property "Device Type" "SC22U16V5MX-4-GP_SMD-BCG5-SC22A"
			(at -0.0762 -8.2677 0)
			(unlocked yes)
			(layer "F.Fab")
			(hide yes)
			(effects
				(font
					(size 1.27 1.016)
					(thickness 0.1524)
				)
			)
		)
		(duplicate_pad_numbers_are_jumpers no)
		(fp_line
			(start 0.635 0)
			(end -0.635 0)
			(stroke
				(width 0.508)
				(type default)
			)
			(layer "F.SilkS")
		)
		(fp_rect
			(start -0.9652 1.778)
			(end 0.9652 -1.778)
			(stroke
				(width 0)
				(type default)
			)
			(fill no)
			(layer "F.CrtYd")
		)
		(fp_poly
			(pts
				(xy -0.9652 -1.778) (xy 0.9652 -1.778) (xy 0.9652 1.778) (xy -0.9652 1.778)
			)
			(stroke
				(width 0)
				(type default)
			)
			(fill no)
			(layer "F.Fab")
		)
		(pad "1" smd rect
			(at 0 -0.9652)
			(size 1.397 1.143)
			(layers "F.Cu" "F.Mask" "F.Paste")
			(net "VR_FET_SW_P12V_STBY_PVCCIN_CPU0")
		)
		(pad "2" smd rect
			(at 0 0.9652)
			(size 1.397 1.143)
			(layers "F.Cu" "F.Mask" "F.Paste")
			(net "GND")
		)
	)
	(footprint ""
		(layer "F.Cu")
		(at 338.836 -18.161 -90)
		(property "Reference" "R12W26"
			(at -0.8382 -0.67818 270)
			(unlocked yes)
			(layer "F.SilkS")
			(effects
				(font
					(size 0.4064 0.254)
					(thickness 0.1524)
				)
				(justify left)
			)
		)
		(property "Value" ""
			(at 0 0 270)
			(layer "F.Fab")
			(effects
				(font
					(size 1.27 1.27)
				)
			)
		)
		(duplicate_pad_numbers_are_jumpers no)
		(fp_poly
			(pts
				(xy -0.2794 -0.1016) (xy 0.2794 -0.1016) (xy 0.2794 0.9906) (xy -0.2794 0.9906)
			)
			(stroke
				(width 0)
				(type default)
			)
			(fill no)
			(layer "F.CrtYd")
		)
		(fp_line
			(start -0.2794 0.9906)
			(end 0.2794 0.9906)
			(stroke
				(width 0.1)
				(type default)
			)
			(layer "F.Fab")
		)
		(fp_line
			(start 0.2794 0.9906)
			(end 0.2794 -0.1016)
			(stroke
				(width 0.1)
				(type default)
			)
			(layer "F.Fab")
		)
		(fp_line
			(start -0.2794 -0.1016)
			(end -0.2794 0.9906)
			(stroke
				(width 0.1)
				(type default)
			)
			(layer "F.Fab")
		)
		(fp_line
			(start 0.2794 -0.1016)
			(end -0.2794 -0.1016)
			(stroke
				(width 0.1)
				(type default)
			)
			(layer "F.Fab")
		)
		(pad "1" smd rect
			(at 0 0 270)
			(size 0.508 0.508)
			(layers "F.Cu" "F.Mask" "F.Paste")
			(net "TP_PVDDQ_ABC_MP1")
		)
		(pad "2" smd rect
			(at 0 0.889 270)
			(size 0.508 0.508)
			(layers "F.Cu" "F.Mask" "F.Paste")
			(net "PWRGD_PVDDQ_ABC")
		)
		(zone
			(layer "F.Cu")
			(hatch none 0.5)
			(connect_pads
				(clearance 0)
			)
			(min_thickness 0.25)
			(keepout
				(tracks not_allowed)
				(vias allowed)
				(pads allowed)
				(copperpour not_allowed)
				(footprints allowed)
			)
			(placement
				(enabled no)
				(sheetname "")
			)
			(fill
				(thermal_gap 0.5)
				(thermal_bridge_width 0.5)
				(island_removal_mode 0)
			)
			(polygon
				(pts
					(xy 338.201 -18.415) (xy 338.201 -17.907) (xy 338.582 -17.907) (xy 338.582 -18.415)
				)
			)
		)
		(zone
			(layer "F.Cu")
			(hatch none 0.5)
			(connect_pads
				(clearance 0)
			)
			(min_thickness 0.25)
			(keepout
				(tracks allowed)
				(vias not_allowed)
				(pads allowed)
				(copperpour not_allowed)
				(footprints allowed)
			)
			(placement
				(enabled no)
				(sheetname "")
			)
			(fill
				(thermal_gap 0.5)
				(thermal_bridge_width 0.5)
				(island_removal_mode 0)
			)
			(polygon
				(pts
					(xy 338.582 -18.415) (xy 338.582 -17.907) (xy 338.201 -17.907) (xy 338.201 -18.415)
				)
			)
		)
	)
)
